# BASEBOARD_FAB2 (Tioga Pass) — schematic netlist excerpt (pin names and nets, part order shuffled) for the footprints in the layout excerpt that follows; sources: Cadence DE-HDL packaged netlist, KiCad conversion of Wiwynn_Tioga_Pass_MB.brd

C6N11  CAP  10UF 16V 10% X6S  pkg 0805  page 204 : A = VR_FET_SW_P12V_STBY_PVCCIN_CPU0 ; B = GND
R6R5  RES  0.0 5% CHIP  pkg 0402  page 214 : A = VR_PVCCIO_CPU1_PH1_VCIN ; B = P5V_STBY
R1U6  RES  10.0K 1% CHIP  pkg 0402  page 154 : A = FM_BIOS_SPI_BMC_CTRL ; B = GND

(kicad_pcb
	(version 20260206)
	(generator "pcbnew")
	(generator_version "10.0")
	(general
		(thickness 1.6)
		(legacy_teardrops no)
	)
	(paper "A4")
	(title_block
		(title "Wiwynn_Tioga_Pass_MB.brd")
		(comment 1 "Tioga Pass / footprints 3435-3437 of 4770")
	)
	(layers
		(0 "F.Cu" signal "TOP")
		(4 "In1.Cu" signal "L2GND")
		(6 "In2.Cu" signal "L3")
		(8 "In3.Cu" signal "L4GND")
		(10 "In4.Cu" signal "L5")
		(12 "In5.Cu" signal "L6GND")
		(14 "In6.Cu" signal "L7VCC")
		(16 "In7.Cu" signal "L8VCC")
		(18 "In8.Cu" signal "L9GND")
		(20 "In9.Cu" signal "L10")
		(22 "In10.Cu" signal "L11GND")
		(24 "In11.Cu" signal "L12")
		(26 "In12.Cu" signal "L13GND")
		(2 "B.Cu" signal "BOTTOM")
		(9 "F.Adhes" user "F.Adhesive")
		(11 "B.Adhes" user "B.Adhesive")
		(13 "F.Paste" user "Package Geometry/Pastemask Top")
		(15 "B.Paste" user "Package Geometry/Pastemask Bottom")
		(5 "F.SilkS" user "Ref Des/Silkscreen Top")
		(7 "B.SilkS" user "Ref Des/Silkscreen Bottom")
		(1 "F.Mask" user "Board Geometry/Soldermask Top")
		(3 "B.Mask" user "Board Geometry/Soldermask Bottom")
		(17 "Dwgs.User" user "User.Drawings")
		(19 "Cmts.User" user "User.Comments")
		(21 "Eco1.User" user "User.Eco1")
		(23 "Eco2.User" user "User.Eco2")
		(25 "Edge.Cuts" user "Board Geometry/Outline")
		(27 "Margin" user)
		(31 "F.CrtYd" user "Package Geometry/Place Bound Top")
		(29 "B.CrtYd" user "Package Geometry/Place Bound Bottom")
		(35 "F.Fab" user "Ref Des/Assembly Top")
		(33 "B.Fab" user "Ref Des/Assembly Bottom")
	)
	(footprint ""
		(layer "B.Cu")
		(at 385.2545 -54.61 90)
		(property "Reference" "R1U6"
			(at 0 0 90)
			(layer "B.SilkS")
			(hide yes)
			(effects
				(font
					(size 1.27 1.27)
				)
				(justify mirror)
			)
		)
		(property "Value" ""
			(at 0 0 90)
			(layer "B.Fab")
			(effects
				(font
					(size 1.27 1.27)
				)
				(justify mirror)
			)
		)
		(duplicate_pad_numbers_are_jumpers no)
		(fp_poly
			(pts
				(xy 0.2794 -0.1016) (xy -0.2794 -0.1016) (xy -0.2794 0.9906) (xy 0.2794 0.9906)
			)
			(stroke
				(width 0)
				(type default)
			)
			(fill no)
			(layer "B.CrtYd")
		)
		(fp_line
			(start 0.2794 -0.1016)
			(end 0.2794 0.9906)
			(stroke
				(width 0.1)
				(type default)
			)
			(layer "B.Fab")
		)
		(fp_line
			(start -0.2794 -0.1016)
			(end 0.2794 -0.1016)
			(stroke
				(width 0.1)
				(type default)
			)
			(layer "B.Fab")
		)
		(fp_line
			(start 0.2794 0.9906)
			(end -0.2794 0.9906)
			(stroke
				(width 0.1)
				(type default)
			)
			(layer "B.Fab")
		)
		(fp_line
			(start -0.2794 0.9906)
			(end -0.2794 -0.1016)
			(stroke
				(width 0.1)
				(type default)
			)
			(layer "B.Fab")
		)
		(pad "1" smd rect
			(at 0 0 270)
			(size 0.508 0.508)
			(layers "B.Cu" "B.Mask" "B.Paste")
			(net "FM_BIOS_SPI_BMC_CTRL")
		)
		(pad "2" smd rect
			(at 0 0.889 270)
			(size 0.508 0.508)
			(layers "B.Cu" "B.Mask" "B.Paste")
			(net "GND")
		)
		(zone
			(layer "B.Cu")
			(hatch none 0.5)
			(connect_pads
				(clearance 0)
			)
			(min_thickness 0.25)
			(keepout
				(tracks allowed)
				(vias not_allowed)
				(pads allowed)
				(copperpour not_allowed)
				(footprints allowed)
			)
			(placement
				(enabled no)
				(sheetname "")
			)
			(fill
				(thermal_gap 0.5)
				(thermal_bridge_width 0.5)
				(island_removal_mode 0)
			)
			(polygon
				(pts
					(xy 385.5085 -54.864) (xy 385.5085 -54.356) (xy 385.8895 -54.356) (xy 385.8895 -54.864)
				)
			)
		)
		(zone
			(layer "B.Cu")
			(hatch none 0.5)
			(connect_pads
				(clearance 0)
			)
			(min_thickness 0.25)
			(keepout
				(tracks not_allowed)
				(vias allowed)
				(pads allowed)
				(copperpour not_allowed)
				(footprints allowed)
			)
			(placement
				(enabled no)
				(sheetname "")
			)
			(fill
				(thermal_gap 0.5)
				(thermal_bridge_width 0.5)
				(island_removal_mode 0)
			)
			(polygon
				(pts
					(xy 385.8895 -54.864) (xy 385.8895 -54.356) (xy 385.5085 -54.356) (xy 385.5085 -54.864)
				)
			)
		)
	)
	(footprint ""
		(layer "B.Cu")
		(at 197.848728 -89.187782 90)
		(property "Reference" "C6N11"
			(at 0 0 90)
			(layer "B.SilkS")
			(hide yes)
			(effects
				(font
					(size 1.27 1.27)
				)
				(justify mirror)
			)
		)
		(property "Value" ""
			(at 0 0 90)
			(layer "B.Fab")
			(effects
				(font
					(size 1.27 1.27)
				)
				(justify mirror)
			)
		)
		(duplicate_pad_numbers_are_jumpers no)
		(fp_rect
			(start -0.7239 -0.2159)
			(end 0.7239 1.9939)
			(stroke
				(width 0)
				(type default)
			)
			(fill no)
			(layer "B.CrtYd")
		)
		(fp_line
			(start 0.7239 -0.2159)
			(end 0.7239 1.9939)
			(stroke
				(width 0.1)
				(type default)
			)
			(layer "B.Fab")
		)
		(fp_line
			(start -0.7239 -0.2159)
			(end 0.7239 -0.2159)
			(stroke
				(width 0.1)
				(type default)
			)
			(layer "B.Fab")
		)
		(fp_line
			(start 0.7239 1.9939)
			(end -0.7239 1.9939)
			(stroke
				(width 0.1)
				(type default)
			)
			(layer "B.Fab")
		)
		(fp_line
			(start -0.7239 1.9939)
			(end -0.7239 -0.2159)
			(stroke
				(width 0.1)
				(type default)
			)
			(layer "B.Fab")
		)
		(pad "1" smd rect
			(at 0 0 270)
			(size 1.27 1.016)
			(layers "B.Cu" "B.Mask" "B.Paste")
			(net "VR_FET_SW_P12V_STBY_PVCCIN_CPU0")
		)
		(pad "2" smd rect
			(at 0 1.778 270)
			(size 1.27 1.016)
			(layers "B.Cu" "B.Mask" "B.Paste")
			(net "GND")
		)
		(zone
			(layer "B.Cu")
			(hatch none 0.5)
			(connect_pads
				(clearance 0)
			)
			(min_thickness 0.25)
			(keepout
				(tracks not_allowed)
				(vias allowed)
				(pads allowed)
				(copperpour not_allowed)
				(footprints allowed)
			)
			(placement
				(enabled no)
				(sheetname "")
			)
			(fill
				(thermal_gap 0.5)
				(thermal_bridge_width 0.5)
				(island_removal_mode 0)
			)
			(polygon
				(pts
					(xy 198.356728 -88.552782) (xy 199.118728 -88.552782) (xy 199.118728 -89.822782) (xy 198.356728 -89.822782)
				)
			)
		)
	)
	(footprint ""
		(layer "B.Cu")
		(at 179.197 -56.769 -90)
		(property "Reference" "R6R5"
			(at 0 0 90)
			(layer "B.SilkS")
			(hide yes)
			(effects
				(font
					(size 1.27 1.27)
				)
				(justify mirror)
			)
		)
		(property "Value" ""
			(at 0 0 90)
			(layer "B.Fab")
			(effects
				(font
					(size 1.27 1.27)
				)
				(justify mirror)
			)
		)
		(duplicate_pad_numbers_are_jumpers no)
		(fp_poly
			(pts
				(xy 0.2794 -0.1016) (xy -0.2794 -0.1016) (xy -0.2794 0.9906) (xy 0.2794 0.9906)
			)
			(stroke
				(width 0)
				(type default)
			)
			(fill no)
			(layer "B.CrtYd")
		)
		(fp_line
			(start -0.2794 0.9906)
			(end -0.2794 -0.1016)
			(stroke
				(width 0.1)
				(type default)
			)
			(layer "B.Fab")
		)
		(fp_line
			(start 0.2794 0.9906)
			(end -0.2794 0.9906)
			(stroke
				(width 0.1)
				(type default)
			)
			(layer "B.Fab")
		)
		(fp_line
			(start -0.2794 -0.1016)
			(end 0.2794 -0.1016)
			(stroke
				(width 0.1)
				(type default)
			)
			(layer "B.Fab")
		)
		(fp_line
			(start 0.2794 -0.1016)
			(end 0.2794 0.9906)
			(stroke
				(width 0.1)
				(type default)
			)
			(layer "B.Fab")
		)
		(pad "1" smd rect
			(at 0 0 90)
			(size 0.508 0.508)
			(layers "B.Cu" "B.Mask" "B.Paste")
			(net "VR_PVCCIO_CPU1_PH1_VCIN")
		)
		(pad "2" smd rect
			(at 0 0.889 90)
			(size 0.508 0.508)
			(layers "B.Cu" "B.Mask" "B.Paste")
			(net "P5V_STBY")
		)
		(zone
			(layer "B.Cu")
			(hatch none 0.5)
			(connect_pads
				(clearance 0)
			)
			(min_thickness 0.25)
			(keepout
				(tracks not_allowed)
				(vias allowed)
				(pads allowed)
				(copperpour not_allowed)
				(footprints allowed)
			)
			(placement
				(enabled no)
				(sheetname "")
			)
			(fill
				(thermal_gap 0.5)
				(thermal_bridge_width 0.5)
				(island_removal_mode 0)
			)
			(polygon
				(pts
					(xy 178.562 -56.515) (xy 178.562 -57.023) (xy 178.943 -57.023) (xy 178.943 -56.515)
				)
			)
		)
		(zone
			(layer "B.Cu")
			(hatch none 0.5)
			(connect_pads
				(clearance 0)
			)
			(min_thickness 0.25)
			(keepout
				(tracks allowed)
				(vias not_allowed)
				(pads allowed)
				(copperpour not_allowed)
				(footprints allowed)
			)
			(placement
				(enabled no)
				(sheetname "")
			)
			(fill
				(thermal_gap 0.5)
				(thermal_bridge_width 0.5)
				(island_removal_mode 0)
			)
			(polygon
				(pts
					(xy 178.943 -56.515) (xy 178.943 -57.023) (xy 178.562 -57.023) (xy 178.562 -56.515)
				)
			)
		)
	)
)
